# S9S_MB_2U (Grand Teton) — schematic netlist excerpt (pin names and nets, part order shuffled) for the footprints in the layout excerpt that follows; sources: Cadence DE-HDL packaged netlist, KiCad conversion of 03242023_DA0F0TMBIJ0_F0T_Motherboard_J_brd_V01_OCP.brd

PC639  Q_CAP  100NF 50V 10% X7R  pkg C0402  page 279 : A = PVCCD_HV_CPU0 ; B = GND
PR224  Q_RES  8.87K 1% EMPTY  pkg 0402LF  page 289 : A = PVCCFA_EHV_FIVRA_CPU1_LSET2 ; B = GND

(kicad_pcb
	(version 20260206)
	(generator "pcbnew")
	(generator_version "10.0")
	(general
		(thickness 1.6)
		(legacy_teardrops no)
	)
	(paper "A4")
	(title_block
		(title "03242023_DA0F0TMBIJ0_F0T_Motherboard_J_brd_V01_OCP.brd")
		(comment 1 "Grand Teton / footprints 210-211 of 6105")
	)
	(layers
		(0 "F.Cu" signal "TOP")
		(4 "In1.Cu" signal "GND")
		(6 "In2.Cu" signal "IN1")
		(8 "In3.Cu" signal "GND1")
		(10 "In4.Cu" signal "IN2")
		(12 "In5.Cu" signal "GND2")
		(14 "In6.Cu" signal "IN3")
		(16 "In7.Cu" signal "GND3")
		(18 "In8.Cu" signal "VCC")
		(20 "In9.Cu" signal "VCC1")
		(22 "In10.Cu" signal "GND4")
		(24 "In11.Cu" signal "IN4")
		(26 "In12.Cu" signal "GND5")
		(28 "In13.Cu" signal "IN5")
		(30 "In14.Cu" signal "GND6")
		(32 "In15.Cu" signal "IN6")
		(34 "In16.Cu" signal "GND7")
		(2 "B.Cu" signal "BOTTOM")
		(9 "F.Adhes" user "F.Adhesive")
		(11 "B.Adhes" user "B.Adhesive")
		(13 "F.Paste" user "Package Geometry/Pastemask Top")
		(15 "B.Paste" user "Package Geometry/Pastemask Bottom")
		(5 "F.SilkS" user "Ref Des/Silkscreen Top")
		(7 "B.SilkS" user "Ref Des/Silkscreen Bottom")
		(1 "F.Mask" user "Board Geometry/Soldermask Top")
		(3 "B.Mask" user "Board Geometry/Soldermask Bottom")
		(17 "Dwgs.User" user "User.Drawings")
		(19 "Cmts.User" user "User.Comments")
		(21 "Eco1.User" user "User.Eco1")
		(23 "Eco2.User" user "User.Eco2")
		(25 "Edge.Cuts" user "Board Geometry/Outline")
		(27 "Margin" user)
		(31 "F.CrtYd" user "Package Geometry/Place Bound Top")
		(29 "B.CrtYd" user "Package Geometry/Place Bound Bottom")
		(35 "F.Fab" user "Ref Des/Assembly Top")
		(33 "B.Fab" user "Ref Des/Assembly Bottom")
	)
	(footprint ""
		(layer "F.Cu")
		(at 49.962054 -358.691942)
		(property "Reference" "PR224"
			(at 0 0 0)
			(layer "F.SilkS")
			(hide yes)
			(effects
				(font
					(size 1.27 1.27)
				)
			)
		)
		(property "Value" ""
			(at 0 0 0)
			(layer "F.Fab")
			(effects
				(font
					(size 1.27 1.27)
				)
			)
		)
		(duplicate_pad_numbers_are_jumpers no)
		(fp_line
			(start -0.7874 -0.4064)
			(end 0.7874 -0.4064)
			(stroke
				(width 0.1524)
				(type default)
			)
			(layer "F.SilkS")
		)
		(fp_line
			(start -0.7874 0.4064)
			(end -0.7874 -0.4064)
			(stroke
				(width 0.1524)
				(type default)
			)
			(layer "F.SilkS")
		)
		(fp_line
			(start 0.7874 -0.4064)
			(end 0.7874 0.4064)
			(stroke
				(width 0.1524)
				(type default)
			)
			(layer "F.SilkS")
		)
		(fp_line
			(start 0.7874 0.4064)
			(end -0.7874 0.4064)
			(stroke
				(width 0.1524)
				(type default)
			)
			(layer "F.SilkS")
		)
		(fp_line
			(start -0.67945 -0.305054)
			(end -0.12065 -0.305054)
			(stroke
				(width 0.1)
				(type default)
			)
			(layer "F.Fab")
		)
		(fp_line
			(start -0.67945 0.3048)
			(end -0.67945 -0.305054)
			(stroke
				(width 0.1)
				(type default)
			)
			(layer "F.Fab")
		)
		(fp_line
			(start -0.12065 -0.305054)
			(end -0.12065 -0.2794)
			(stroke
				(width 0.1)
				(type default)
			)
			(layer "F.Fab")
		)
		(fp_line
			(start -0.12065 -0.2794)
			(end 0.12065 -0.2794)
			(stroke
				(width 0.1)
				(type default)
			)
			(layer "F.Fab")
		)
		(fp_line
			(start -0.12065 0.2794)
			(end -0.12065 0.3048)
			(stroke
				(width 0.1)
				(type default)
			)
			(layer "F.Fab")
		)
		(fp_line
			(start -0.12065 0.3048)
			(end -0.67945 0.3048)
			(stroke
				(width 0.1)
				(type default)
			)
			(layer "F.Fab")
		)
		(fp_line
			(start 0.120396 0.2794)
			(end -0.12065 0.2794)
			(stroke
				(width 0.1)
				(type default)
			)
			(layer "F.Fab")
		)
		(fp_line
			(start 0.120396 0.3048)
			(end 0.120396 0.2794)
			(stroke
				(width 0.1)
				(type default)
			)
			(layer "F.Fab")
		)
		(fp_line
			(start 0.12065 -0.3048)
			(end 0.67945 -0.3048)
			(stroke
				(width 0.1)
				(type default)
			)
			(layer "F.Fab")
		)
		(fp_line
			(start 0.12065 -0.2794)
			(end 0.12065 -0.3048)
			(stroke
				(width 0.1)
				(type default)
			)
			(layer "F.Fab")
		)
		(fp_line
			(start 0.67945 -0.3048)
			(end 0.67945 0.3048)
			(stroke
				(width 0.1)
				(type default)
			)
			(layer "F.Fab")
		)
		(fp_line
			(start 0.67945 0.3048)
			(end 0.120396 0.3048)
			(stroke
				(width 0.1)
				(type default)
			)
			(layer "F.Fab")
		)
		(pad "1" smd circle
			(at -0.40005 0)
			(size 0 0)
			(layers "F.Cu" "F.Mask" "F.Paste")
			(net "PVCCFA_EHV_FIVRA_CPU1_LSET2")
		)
		(pad "2" smd circle
			(at 0.40005 0)
			(size 0 0)
			(layers "F.Cu" "F.Mask" "F.Paste")
			(net "GND")
		)
	)
	(footprint ""
		(layer "F.Cu")
		(at 407.86812 -166.253668)
		(property "Reference" "PC639"
			(at 0 0 0)
			(layer "F.SilkS")
			(hide yes)
			(effects
				(font
					(size 1.27 1.27)
				)
			)
		)
		(property "Value" ""
			(at 0 0 0)
			(layer "F.Fab")
			(effects
				(font
					(size 1.27 1.27)
				)
			)
		)
		(duplicate_pad_numbers_are_jumpers no)
		(fp_line
			(start -0.7874 -0.4064)
			(end 0.7874 -0.4064)
			(stroke
				(width 0.1524)
				(type default)
			)
			(layer "F.SilkS")
		)
		(fp_line
			(start -0.7874 0.4064)
			(end -0.7874 -0.4064)
			(stroke
				(width 0.1524)
				(type default)
			)
			(layer "F.SilkS")
		)
		(fp_line
			(start 0.7874 -0.4064)
			(end 0.7874 0.4064)
			(stroke
				(width 0.1524)
				(type default)
			)
			(layer "F.SilkS")
		)
		(fp_line
			(start 0.7874 0.4064)
			(end -0.7874 0.4064)
			(stroke
				(width 0.1524)
				(type default)
			)
			(layer "F.SilkS")
		)
		(fp_line
			(start -0.67945 -0.305054)
			(end -0.12065 -0.305054)
			(stroke
				(width 0.1)
				(type default)
			)
			(layer "F.Fab")
		)
		(fp_line
			(start -0.67945 0.3048)
			(end -0.67945 -0.305054)
			(stroke
				(width 0.1)
				(type default)
			)
			(layer "F.Fab")
		)
		(fp_line
			(start -0.12065 -0.305054)
			(end -0.12065 -0.2794)
			(stroke
				(width 0.1)
				(type default)
			)
			(layer "F.Fab")
		)
		(fp_line
			(start -0.12065 -0.2794)
			(end 0.12065 -0.2794)
			(stroke
				(width 0.1)
				(type default)
			)
			(layer "F.Fab")
		)
		(fp_line
			(start -0.12065 0.2794)
			(end -0.12065 0.3048)
			(stroke
				(width 0.1)
				(type default)
			)
			(layer "F.Fab")
		)
		(fp_line
			(start -0.12065 0.3048)
			(end -0.67945 0.3048)
			(stroke
				(width 0.1)
				(type default)
			)
			(layer "F.Fab")
		)
		(fp_line
			(start 0.120396 0.2794)
			(end -0.12065 0.2794)
			(stroke
				(width 0.1)
				(type default)
			)
			(layer "F.Fab")
		)
		(fp_line
			(start 0.120396 0.3048)
			(end 0.120396 0.2794)
			(stroke
				(width 0.1)
				(type default)
			)
			(layer "F.Fab")
		)
		(fp_line
			(start 0.12065 -0.3048)
			(end 0.67945 -0.3048)
			(stroke
				(width 0.1)
				(type default)
			)
			(layer "F.Fab")
		)
		(fp_line
			(start 0.12065 -0.2794)
			(end 0.12065 -0.3048)
			(stroke
				(width 0.1)
				(type default)
			)
			(layer "F.Fab")
		)
		(fp_line
			(start 0.67945 -0.3048)
			(end 0.67945 0.3048)
			(stroke
				(width 0.1)
				(type default)
			)
			(layer "F.Fab")
		)
		(fp_line
			(start 0.67945 0.3048)
			(end 0.120396 0.3048)
			(stroke
				(width 0.1)
				(type default)
			)
			(layer "F.Fab")
		)
		(pad "1" smd circle
			(at -0.40005 0)
			(size 0 0)
			(layers "F.Cu" "F.Mask" "F.Paste")
			(net "PVCCD_HV_CPU0")
		)
		(pad "2" smd circle
			(at 0.40005 0)
			(size 0 0)
			(layers "F.Cu" "F.Mask" "F.Paste")
			(net "GND")
		)
	)
)
